(kicad_pcb
	(version 20260206)
	(generator "pcbnew")
	(generator_version "10.0")
	(general
		(thickness 1.6)
		(legacy_teardrops no)
	)
	(paper "A4")
	(title_block
		(title "03242023_DA0F0TMBIJ0_F0T_Motherboard_J_brd_V01_OCP.brd")
		(comment 1 "Grand Teton / footprints 3698-3702 of 6105")
	)
	(layers
		(0 "F.Cu" signal "TOP")
		(4 "In1.Cu" signal "GND")
		(6 "In2.Cu" signal "IN1")
		(8 "In3.Cu" signal "GND1")
		(10 "In4.Cu" signal "IN2")
		(12 "In5.Cu" signal "GND2")
		(14 "In6.Cu" signal "IN3")
		(16 "In7.Cu" signal "GND3")
		(18 "In8.Cu" signal "VCC")
		(20 "In9.Cu" signal "VCC1")
		(22 "In10.Cu" signal "GND4")
		(24 "In11.Cu" signal "IN4")
		(26 "In12.Cu" signal "GND5")
		(28 "In13.Cu" signal "IN5")
		(30 "In14.Cu" signal "GND6")
		(32 "In15.Cu" signal "IN6")
		(34 "In16.Cu" signal "GND7")
		(2 "B.Cu" signal "BOTTOM")
		(9 "F.Adhes" user "F.Adhesive")
		(11 "B.Adhes" user "B.Adhesive")
		(13 "F.Paste" user "Package Geometry/Pastemask Top")
		(15 "B.Paste" user "Package Geometry/Pastemask Bottom")
		(5 "F.SilkS" user "Ref Des/Silkscreen Top")
		(7 "B.SilkS" user "Ref Des/Silkscreen Bottom")
		(1 "F.Mask" user "Board Geometry/Soldermask Top")
		(3 "B.Mask" user "Board Geometry/Soldermask Bottom")
		(17 "Dwgs.User" user "User.Drawings")
		(19 "Cmts.User" user "User.Comments")
		(21 "Eco1.User" user "User.Eco1")
		(23 "Eco2.User" user "User.Eco2")
		(25 "Edge.Cuts" user "Board Geometry/Outline")
		(27 "Margin" user)
		(31 "F.CrtYd" user "Package Geometry/Place Bound Top")
		(29 "B.CrtYd" user "Package Geometry/Place Bound Bottom")
		(35 "F.Fab" user "Ref Des/Assembly Top")
		(33 "B.Fab" user "Ref Des/Assembly Bottom")
	)
	(footprint ""
		(layer "F.Cu")
		(at 370.021358 -107.333034 90)
		(property "Reference" "R1832"
			(at 0 0 90)
			(layer "F.SilkS")
			(hide yes)
			(effects
				(font
					(size 1.27 1.27)
				)
			)
		)
		(property "Value" ""
			(at 0 0 90)
			(layer "F.Fab")
			(effects
				(font
					(size 1.27 1.27)
				)
			)
		)
		(duplicate_pad_numbers_are_jumpers no)
		(fp_line
			(start 0.7874 -0.4064)
			(end 0.7874 0.4064)
			(stroke
				(width 0.1524)
				(type default)
			)
			(layer "F.SilkS")
		)
		(fp_line
			(start -0.7874 -0.4064)
			(end 0.7874 -0.4064)
			(stroke
				(width 0.1524)
				(type default)
			)
			(layer "F.SilkS")
		)
		(fp_line
			(start 0.7874 0.4064)
			(end -0.7874 0.4064)
			(stroke
				(width 0.1524)
				(type default)
			)
			(layer "F.SilkS")
		)
		(fp_line
			(start -0.7874 0.4064)
			(end -0.7874 -0.4064)
			(stroke
				(width 0.1524)
				(type default)
			)
			(layer "F.SilkS")
		)
		(fp_line
			(start -0.12065 -0.305054)
			(end -0.12065 -0.2794)
			(stroke
				(width 0.1)
				(type default)
			)
			(layer "F.Fab")
		)
		(fp_line
			(start -0.67945 -0.305054)
			(end -0.12065 -0.305054)
			(stroke
				(width 0.1)
				(type default)
			)
			(layer "F.Fab")
		)
		(fp_line
			(start 0.67945 -0.3048)
			(end 0.67945 0.3048)
			(stroke
				(width 0.1)
				(type default)
			)
			(layer "F.Fab")
		)
		(fp_line
			(start 0.12065 -0.3048)
			(end 0.67945 -0.3048)
			(stroke
				(width 0.1)
				(type default)
			)
			(layer "F.Fab")
		)
		(fp_line
			(start 0.12065 -0.2794)
			(end 0.12065 -0.3048)
			(stroke
				(width 0.1)
				(type default)
			)
			(layer "F.Fab")
		)
		(fp_line
			(start -0.12065 -0.2794)
			(end 0.12065 -0.2794)
			(stroke
				(width 0.1)
				(type default)
			)
			(layer "F.Fab")
		)
		(fp_line
			(start 0.120396 0.2794)
			(end -0.12065 0.2794)
			(stroke
				(width 0.1)
				(type default)
			)
			(layer "F.Fab")
		)
		(fp_line
			(start -0.12065 0.2794)
			(end -0.12065 0.3048)
			(stroke
				(width 0.1)
				(type default)
			)
			(layer "F.Fab")
		)
		(fp_line
			(start 0.67945 0.3048)
			(end 0.120396 0.3048)
			(stroke
				(width 0.1)
				(type default)
			)
			(layer "F.Fab")
		)
		(fp_line
			(start 0.120396 0.3048)
			(end 0.120396 0.2794)
			(stroke
				(width 0.1)
				(type default)
			)
			(layer "F.Fab")
		)
		(fp_line
			(start -0.12065 0.3048)
			(end -0.67945 0.3048)
			(stroke
				(width 0.1)
				(type default)
			)
			(layer "F.Fab")
		)
		(fp_line
			(start -0.67945 0.3048)
			(end -0.67945 -0.305054)
			(stroke
				(width 0.1)
				(type default)
			)
			(layer "F.Fab")
		)
		(pad "1" smd circle
			(at -0.40005 0 90)
			(size 0 0)
			(layers "F.Cu" "F.Mask" "F.Paste")
			(net "JTAG_BMC_DBP_PREQ_N")
		)
		(pad "2" smd circle
			(at 0.40005 0 90)
			(size 0 0)
			(layers "F.Cu" "F.Mask" "F.Paste")
			(net "JTAG_DBP_BMC_PREQ_R_N")
		)
	)
	(footprint ""
		(layer "F.Cu")
		(at 328.647044 -342.976962)
		(property "Reference" "PU7_P0_7"
			(at -10.682224 -1.070356 0)
			(unlocked yes)
			(layer "F.SilkS")
			(effects
				(font
					(size 0.7874 0.5842)
					(thickness 0.1524)
				)
				(justify left)
			)
		)
		(property "Value" ""
			(at 0 0 0)
			(layer "F.Fab")
			(effects
				(font
					(size 1.27 1.27)
				)
			)
		)
		(duplicate_pad_numbers_are_jumpers no)
		(fp_line
			(start -2.500122 -2.999994)
			(end -2.24409 -2.999994)
			(stroke
				(width 0.1524)
				(type default)
			)
			(layer "F.SilkS")
		)
		(fp_line
			(start -2.500122 -2.529078)
			(end -2.500122 -2.999994)
			(stroke
				(width 0.1524)
				(type default)
			)
			(layer "F.SilkS")
		)
		(fp_line
			(start -2.500122 0.6604)
			(end -2.500122 0.229108)
			(stroke
				(width 0.1524)
				(type default)
			)
			(layer "F.SilkS")
		)
		(fp_line
			(start -2.500122 2.999994)
			(end -2.500122 2.339594)
			(stroke
				(width 0.1524)
				(type default)
			)
			(layer "F.SilkS")
		)
		(fp_line
			(start -2.2987 2.999994)
			(end -2.500122 2.999994)
			(stroke
				(width 0.1524)
				(type default)
			)
			(layer "F.SilkS")
		)
		(fp_line
			(start 2.31394 -2.999994)
			(end 2.500122 -2.999994)
			(stroke
				(width 0.1524)
				(type default)
			)
			(layer "F.SilkS")
		)
		(fp_line
			(start 2.500122 -2.999994)
			(end 2.500122 -2.44348)
			(stroke
				(width 0.1524)
				(type default)
			)
			(layer "F.SilkS")
		)
		(fp_line
			(start 2.500122 2.339594)
			(end 2.500122 2.999994)
			(stroke
				(width 0.1524)
				(type default)
			)
			(layer "F.SilkS")
		)
		(fp_line
			(start 2.500122 2.999994)
			(end 2.2987 2.999994)
			(stroke
				(width 0.1524)
				(type default)
			)
			(layer "F.SilkS")
		)
		(fp_poly
			(pts
				(xy -2.176272 -3.637534) (xy -2.684272 -2.621534) (xy -3.192272 -3.637534)
			)
			(stroke
				(width 0)
				(type default)
			)
			(fill yes)
			(layer "F.SilkS")
		)
		(fp_line
			(start -2.500122 -2.999994)
			(end 2.500122 -2.999994)
			(stroke
				(width 0.1)
				(type default)
			)
			(layer "F.Fab")
		)
		(fp_line
			(start -2.500122 2.999994)
			(end -2.500122 -2.999994)
			(stroke
				(width 0.1)
				(type default)
			)
			(layer "F.Fab")
		)
		(fp_line
			(start 2.500122 -2.999994)
			(end 2.500122 2.999994)
			(stroke
				(width 0.1)
				(type default)
			)
			(layer "F.Fab")
		)
		(fp_line
			(start 2.500122 2.999994)
			(end -2.500122 2.999994)
			(stroke
				(width 0.1)
				(type default)
			)
			(layer "F.Fab")
		)
		(fp_poly
			(pts
				(xy -4.218432 -2.783078) (xy -4.218432 -1.767078) (xy -3.202432 -2.275078)
			)
			(stroke
				(width 0)
				(type default)
			)
			(fill yes)
			(layer "F.Fab")
		)
		(pad "1" smd rect
			(at -2.400046 -2.275078 90)
			(size 0.2286 0.6096)
			(layers "F.Cu" "F.Mask" "F.Paste")
			(net "PVCCIN_CPU0_VOS7")
		)
		(pad "2" smd rect
			(at -2.400046 -1.82499 90)
			(size 0.2286 0.6096)
			(layers "F.Cu" "F.Mask" "F.Paste")
			(net "GND")
		)
		(pad "3" smd rect
			(at -2.400046 -1.374902 90)
			(size 0.2286 0.6096)
			(layers "F.Cu" "F.Mask" "F.Paste")
			(net "PVCCIN_CPU0_VDD7")
		)
		(pad "4" smd rect
			(at -2.400046 -0.925068 90)
			(size 0.2286 0.6096)
			(layers "F.Cu" "F.Mask" "F.Paste")
			(net "PVCCIN_CPU0_PVCC")
		)
		(pad "5" smd rect
			(at -2.400046 -0.47498 90)
			(size 0.2286 0.6096)
			(layers "F.Cu" "F.Mask" "F.Paste")
			(net "GND")
		)
		(pad "6" smd rect
			(at -2.400046 -0.024892 90)
			(size 0.2286 0.6096)
			(layers "F.Cu" "F.Mask" "F.Paste")
			(net "Net_8562")
		)
		(pad "7_9-20_24" smd circle
			(at 0 1.150112 90)
			(size 0 0)
			(layers "F.Cu" "F.Mask" "F.Paste")
			(net "GND")
		)
		(pad "10_19" smd rect
			(at 0 2.899918 90)
			(size 0.6096 4.318)
			(layers "F.Cu" "F.Mask" "F.Paste")
			(net "SW_PVCCIN_CPU0_SW7")
		)
		(pad "25_29" smd rect
			(at 1.549908 -1.279906 270)
			(size 2.0574 2.3114)
			(layers "F.Cu" "F.Mask" "F.Paste")
			(net "SW_P12V_PVCCIN_CPU0_FLT")
		)
		(pad "30" smd rect
			(at 2.05994 -2.899918)
			(size 0.2286 0.6096)
			(layers "F.Cu" "F.Mask" "F.Paste")
			(net "SW_P12V_PVCCIN_CPU0_FLT")
		)
		(pad "31" smd rect
			(at 1.610106 -2.899918)
			(size 0.2286 0.6096)
			(layers "F.Cu" "F.Mask" "F.Paste")
			(net "Net_8563")
		)
		(pad "32" smd rect
			(at 1.160018 -2.899918)
			(size 0.2286 0.6096)
			(layers "F.Cu" "F.Mask" "F.Paste")
			(net "SW_PVCCIN_CPU0_BOOTR7")
		)
		(pad "33" smd rect
			(at 0.70993 -2.899918)
			(size 0.2286 0.6096)
			(layers "F.Cu" "F.Mask" "F.Paste")
			(net "SW_PVCCIN_CPU0_BOOT7")
		)
		(pad "34" smd rect
			(at 0.260096 -2.899918)
			(size 0.2286 0.6096)
			(layers "F.Cu" "F.Mask" "F.Paste")
			(net "PVCCIN_CPU0_PWM7")
		)
		(pad "35" smd rect
			(at -0.189992 -2.899918)
			(size 0.2286 0.6096)
			(layers "F.Cu" "F.Mask" "F.Paste")
			(net "PVCCIN_CPU0_VDD7")
		)
		(pad "36" smd rect
			(at -0.64008 -2.899918)
			(size 0.2286 0.6096)
			(layers "F.Cu" "F.Mask" "F.Paste")
			(net "PVCCIN_CPU0_ATSEN")
		)
		(pad "37" smd rect
			(at -1.089914 -2.899918)
			(size 0.2286 0.6096)
			(layers "F.Cu" "F.Mask" "F.Paste")
			(net "PVCCIN_CPU0_LSET7")
		)
		(pad "38" smd rect
			(at -1.540002 -2.899918)
			(size 0.2286 0.6096)
			(layers "F.Cu" "F.Mask" "F.Paste")
			(net "PVCCIN_CPU0_IMON7")
		)
		(pad "39" smd rect
			(at -1.99009 -2.899918)
			(size 0.2286 0.6096)
			(layers "F.Cu" "F.Mask" "F.Paste")
			(net "PVCCIN_CPU0_VREF")
		)
		(pad "40" smd rect
			(at -0.87503 -1.27508)
			(size 1.7526 1.9558)
			(layers "F.Cu" "F.Mask" "F.Paste")
			(net "GND")
		)
		(pad "41" smd rect
			(at -1.525016 0.249936 270)
			(size 0.3048 0.4572)
			(layers "F.Cu" "F.Mask" "F.Paste")
			(net "Net_8561")
		)
		(zone
			(layer "F.Cu")
			(hatch none 0.5)
			(connect_pads
				(clearance 0)
			)
			(min_thickness 0.25)
			(keepout
				(tracks not_allowed)
				(vias allowed)
				(pads allowed)
				(copperpour not_allowed)
				(footprints allowed)
			)
			(placement
				(enabled no)
				(sheetname "")
			)
			(fill
				(thermal_gap 0.5)
				(thermal_bridge_width 0.5)
				(island_removal_mode 0)
			)
			(polygon
				(pts
					(xy 326.602598 -344.658188) (xy 326.844914 -344.658188) (xy 326.844914 -343.624408) (xy 326.602598 -343.624408)
				)
			)
		)
		(zone
			(layer "F.Cu")
			(hatch none 0.5)
			(connect_pads
				(clearance 0)
			)
			(min_thickness 0.25)
			(keepout
				(tracks not_allowed)
				(vias allowed)
				(pads allowed)
				(copperpour not_allowed)
				(footprints allowed)
			)
			(placement
				(enabled no)
				(sheetname "")
			)
			(fill
				(thermal_gap 0.5)
				(thermal_bridge_width 0.5)
				(island_removal_mode 0)
			)
			(polygon
				(pts
					(xy 326.146922 -339.976968) (xy 326.146922 -340.655148) (xy 331.10678 -340.655148) (xy 331.10678 -339.976968)
					(xy 330.856844 -339.976968) (xy 330.856844 -340.432644) (xy 326.437244 -340.432644) (xy 326.437244 -339.976968)
				)
			)
		)
	)
	(footprint ""
		(layer "F.Cu")
		(at 193.089022 -24.091392 -90)
		(property "Reference" "R4015"
			(at 0 0 270)
			(layer "F.SilkS")
			(hide yes)
			(effects
				(font
					(size 1.27 1.27)
				)
			)
		)
		(property "Value" ""
			(at 0 0 270)
			(layer "F.Fab")
			(effects
				(font
					(size 1.27 1.27)
				)
			)
		)
		(duplicate_pad_numbers_are_jumpers no)
		(fp_line
			(start -0.7874 0.4064)
			(end -0.7874 -0.4064)
			(stroke
				(width 0.1524)
				(type default)
			)
			(layer "F.SilkS")
		)
		(fp_line
			(start 0.7874 0.4064)
			(end -0.7874 0.4064)
			(stroke
				(width 0.1524)
				(type default)
			)
			(layer "F.SilkS")
		)
		(fp_line
			(start -0.7874 -0.4064)
			(end 0.7874 -0.4064)
			(stroke
				(width 0.1524)
				(type default)
			)
			(layer "F.SilkS")
		)
		(fp_line
			(start 0.7874 -0.4064)
			(end 0.7874 0.4064)
			(stroke
				(width 0.1524)
				(type default)
			)
			(layer "F.SilkS")
		)
		(fp_line
			(start -0.67945 0.3048)
			(end -0.67945 -0.305054)
			(stroke
				(width 0.1)
				(type default)
			)
			(layer "F.Fab")
		)
		(fp_line
			(start -0.12065 0.3048)
			(end -0.67945 0.3048)
			(stroke
				(width 0.1)
				(type default)
			)
			(layer "F.Fab")
		)
		(fp_line
			(start 0.120396 0.3048)
			(end 0.120396 0.2794)
			(stroke
				(width 0.1)
				(type default)
			)
			(layer "F.Fab")
		)
		(fp_line
			(start 0.67945 0.3048)
			(end 0.120396 0.3048)
			(stroke
				(width 0.1)
				(type default)
			)
			(layer "F.Fab")
		)
		(fp_line
			(start -0.12065 0.2794)
			(end -0.12065 0.3048)
			(stroke
				(width 0.1)
				(type default)
			)
			(layer "F.Fab")
		)
		(fp_line
			(start 0.120396 0.2794)
			(end -0.12065 0.2794)
			(stroke
				(width 0.1)
				(type default)
			)
			(layer "F.Fab")
		)
		(fp_line
			(start -0.12065 -0.2794)
			(end 0.12065 -0.2794)
			(stroke
				(width 0.1)
				(type default)
			)
			(layer "F.Fab")
		)
		(fp_line
			(start 0.12065 -0.2794)
			(end 0.12065 -0.3048)
			(stroke
				(width 0.1)
				(type default)
			)
			(layer "F.Fab")
		)
		(fp_line
			(start 0.12065 -0.3048)
			(end 0.67945 -0.3048)
			(stroke
				(width 0.1)
				(type default)
			)
			(layer "F.Fab")
		)
		(fp_line
			(start 0.67945 -0.3048)
			(end 0.67945 0.3048)
			(stroke
				(width 0.1)
				(type default)
			)
			(layer "F.Fab")
		)
		(fp_line
			(start -0.67945 -0.305054)
			(end -0.12065 -0.305054)
			(stroke
				(width 0.1)
				(type default)
			)
			(layer "F.Fab")
		)
		(fp_line
			(start -0.12065 -0.305054)
			(end -0.12065 -0.2794)
			(stroke
				(width 0.1)
				(type default)
			)
			(layer "F.Fab")
		)
		(pad "1" smd circle
			(at -0.40005 0 270)
			(size 0 0)
			(layers "F.Cu" "F.Mask" "F.Paste")
			(net "P3V3_AUX")
		)
		(pad "2" smd circle
			(at 0.40005 0 270)
			(size 0 0)
			(layers "F.Cu" "F.Mask" "F.Paste")
			(net "HP_LVC3_SCM_HSC_PWRGD")
		)
	)
	(footprint ""
		(layer "F.Cu")
		(at 337.650328 -402.371052 -90)
		(property "Reference" "C1557"
			(at 0 0 270)
			(layer "F.SilkS")
			(hide yes)
			(effects
				(font
					(size 1.27 1.27)
				)
			)
		)
		(property "Value" ""
			(at 0 0 270)
			(layer "F.Fab")
			(effects
				(font
					(size 1.27 1.27)
				)
			)
		)
		(duplicate_pad_numbers_are_jumpers no)
		(fp_line
			(start -0.299974 0.150114)
			(end -0.299974 -0.150114)
			(stroke
				(width 0.1)
				(type default)
			)
			(layer "F.Fab")
		)
		(fp_line
			(start 0.299974 0.150114)
			(end -0.299974 0.150114)
			(stroke
				(width 0.1)
				(type default)
			)
			(layer "F.Fab")
		)
		(fp_line
			(start -0.299974 -0.150114)
			(end 0.299974 -0.150114)
			(stroke
				(width 0.1)
				(type default)
			)
			(layer "F.Fab")
		)
		(fp_line
			(start 0.299974 -0.150114)
			(end 0.299974 0.150114)
			(stroke
				(width 0.1)
				(type default)
			)
			(layer "F.Fab")
		)
		(pad "1" smd rect
			(at -0.2667 0 270)
			(size 0.3048 0.381)
			(layers "F.Cu" "F.Mask" "F.Paste")
			(net "P5E_CPU0_PE4_TX_C_DP<11>")
		)
		(pad "2" smd rect
			(at 0.2667 0 270)
			(size 0.3048 0.381)
			(layers "F.Cu" "F.Mask" "F.Paste")
			(net "P5E_CPU0_PE4_TX_DP<11>")
		)
	)
	(footprint ""
		(layer "F.Cu")
		(at 72.766174 -65.082674 -90)
		(property "Reference" "R3081"
			(at 0 0 270)
			(layer "F.SilkS")
			(hide yes)
			(effects
				(font
					(size 1.27 1.27)
				)
			)
		)
		(property "Value" ""
			(at 0 0 270)
			(layer "F.Fab")
			(effects
				(font
					(size 1.27 1.27)
				)
			)
		)
		(duplicate_pad_numbers_are_jumpers no)
		(fp_line
			(start -0.7874 0.4064)
			(end -0.7874 -0.4064)
			(stroke
				(width 0.1524)
				(type default)
			)
			(layer "F.SilkS")
		)
		(fp_line
			(start 0.7874 0.4064)
			(end -0.7874 0.4064)
			(stroke
				(width 0.1524)
				(type default)
			)
			(layer "F.SilkS")
		)
		(fp_line
			(start -0.7874 -0.4064)
			(end 0.7874 -0.4064)
			(stroke
				(width 0.1524)
				(type default)
			)
			(layer "F.SilkS")
		)
		(fp_line
			(start 0.7874 -0.4064)
			(end 0.7874 0.4064)
			(stroke
				(width 0.1524)
				(type default)
			)
			(layer "F.SilkS")
		)
		(fp_line
			(start -0.67945 0.3048)
			(end -0.67945 -0.305054)
			(stroke
				(width 0.1)
				(type default)
			)
			(layer "F.Fab")
		)
		(fp_line
			(start -0.12065 0.3048)
			(end -0.67945 0.3048)
			(stroke
				(width 0.1)
				(type default)
			)
			(layer "F.Fab")
		)
		(fp_line
			(start 0.120396 0.3048)
			(end 0.120396 0.2794)
			(stroke
				(width 0.1)
				(type default)
			)
			(layer "F.Fab")
		)
		(fp_line
			(start 0.67945 0.3048)
			(end 0.120396 0.3048)
			(stroke
				(width 0.1)
				(type default)
			)
			(layer "F.Fab")
		)
		(fp_line
			(start -0.12065 0.2794)
			(end -0.12065 0.3048)
			(stroke
				(width 0.1)
				(type default)
			)
			(layer "F.Fab")
		)
		(fp_line
			(start 0.120396 0.2794)
			(end -0.12065 0.2794)
			(stroke
				(width 0.1)
				(type default)
			)
			(layer "F.Fab")
		)
		(fp_line
			(start -0.12065 -0.2794)
			(end 0.12065 -0.2794)
			(stroke
				(width 0.1)
				(type default)
			)
			(layer "F.Fab")
		)
		(fp_line
			(start 0.12065 -0.2794)
			(end 0.12065 -0.3048)
			(stroke
				(width 0.1)
				(type default)
			)
			(layer "F.Fab")
		)
		(fp_line
			(start 0.12065 -0.3048)
			(end 0.67945 -0.3048)
			(stroke
				(width 0.1)
				(type default)
			)
			(layer "F.Fab")
		)
		(fp_line
			(start 0.67945 -0.3048)
			(end 0.67945 0.3048)
			(stroke
				(width 0.1)
				(type default)
			)
			(layer "F.Fab")
		)
		(fp_line
			(start -0.67945 -0.305054)
			(end -0.12065 -0.305054)
			(stroke
				(width 0.1)
				(type default)
			)
			(layer "F.Fab")
		)
		(fp_line
			(start -0.12065 -0.305054)
			(end -0.12065 -0.2794)
			(stroke
				(width 0.1)
				(type default)
			)
			(layer "F.Fab")
		)
		(pad "1" smd circle
			(at -0.40005 0 270)
			(size 0 0)
			(layers "F.Cu" "F.Mask" "F.Paste")
			(net "LED_RST_PLD_CPU0_DRAM_GH_N")
		)
		(pad "2" smd circle
			(at 0.40005 0 270)
			(size 0 0)
			(layers "F.Cu" "F.Mask" "F.Paste")
			(net "P3V3_AUX")
		)
	)
)
